(kicad_pcb
	(version 20260206)
	(generator "pcbnew")
	(generator_version "10.0")
	(general
		(thickness 1.6)
		(legacy_teardrops no)
	)
	(paper "A4")
	(title_block
		(title "03242023_DA0F0TMBIJ0_F0T_Motherboard_J_brd_V01_OCP.brd")
		(comment 1 "Grand Teton / footprints 773-778 of 6105")
	)
	(layers
		(0 "F.Cu" signal "TOP")
		(4 "In1.Cu" signal "GND")
		(6 "In2.Cu" signal "IN1")
		(8 "In3.Cu" signal "GND1")
		(10 "In4.Cu" signal "IN2")
		(12 "In5.Cu" signal "GND2")
		(14 "In6.Cu" signal "IN3")
		(16 "In7.Cu" signal "GND3")
		(18 "In8.Cu" signal "VCC")
		(20 "In9.Cu" signal "VCC1")
		(22 "In10.Cu" signal "GND4")
		(24 "In11.Cu" signal "IN4")
		(26 "In12.Cu" signal "GND5")
		(28 "In13.Cu" signal "IN5")
		(30 "In14.Cu" signal "GND6")
		(32 "In15.Cu" signal "IN6")
		(34 "In16.Cu" signal "GND7")
		(2 "B.Cu" signal "BOTTOM")
		(9 "F.Adhes" user "F.Adhesive")
		(11 "B.Adhes" user "B.Adhesive")
		(13 "F.Paste" user "Package Geometry/Pastemask Top")
		(15 "B.Paste" user "Package Geometry/Pastemask Bottom")
		(5 "F.SilkS" user "Ref Des/Silkscreen Top")
		(7 "B.SilkS" user "Ref Des/Silkscreen Bottom")
		(1 "F.Mask" user "Board Geometry/Soldermask Top")
		(3 "B.Mask" user "Board Geometry/Soldermask Bottom")
		(17 "Dwgs.User" user "User.Drawings")
		(19 "Cmts.User" user "User.Comments")
		(21 "Eco1.User" user "User.Eco1")
		(23 "Eco2.User" user "User.Eco2")
		(25 "Edge.Cuts" user "Board Geometry/Outline")
		(27 "Margin" user)
		(31 "F.CrtYd" user "Package Geometry/Place Bound Top")
		(29 "B.CrtYd" user "Package Geometry/Place Bound Bottom")
		(35 "F.Fab" user "Ref Des/Assembly Top")
		(33 "B.Fab" user "Ref Des/Assembly Bottom")
	)
	(footprint ""
		(layer "F.Cu")
		(at 215.646 -111.6838 90)
		(property "Reference" "R4779"
			(at 0 0 90)
			(layer "F.SilkS")
			(hide yes)
			(effects
				(font
					(size 1.27 1.27)
				)
			)
		)
		(property "Value" ""
			(at 0 0 90)
			(layer "F.Fab")
			(effects
				(font
					(size 1.27 1.27)
				)
			)
		)
		(duplicate_pad_numbers_are_jumpers no)
		(fp_line
			(start 0.7874 -0.4064)
			(end 0.7874 0.4064)
			(stroke
				(width 0.1524)
				(type default)
			)
			(layer "F.SilkS")
		)
		(fp_line
			(start -0.7874 -0.4064)
			(end 0.7874 -0.4064)
			(stroke
				(width 0.1524)
				(type default)
			)
			(layer "F.SilkS")
		)
		(fp_line
			(start 0.7874 0.4064)
			(end -0.7874 0.4064)
			(stroke
				(width 0.1524)
				(type default)
			)
			(layer "F.SilkS")
		)
		(fp_line
			(start -0.7874 0.4064)
			(end -0.7874 -0.4064)
			(stroke
				(width 0.1524)
				(type default)
			)
			(layer "F.SilkS")
		)
		(fp_line
			(start -0.12065 -0.305054)
			(end -0.12065 -0.2794)
			(stroke
				(width 0.1)
				(type default)
			)
			(layer "F.Fab")
		)
		(fp_line
			(start -0.67945 -0.305054)
			(end -0.12065 -0.305054)
			(stroke
				(width 0.1)
				(type default)
			)
			(layer "F.Fab")
		)
		(fp_line
			(start 0.67945 -0.3048)
			(end 0.67945 0.3048)
			(stroke
				(width 0.1)
				(type default)
			)
			(layer "F.Fab")
		)
		(fp_line
			(start 0.12065 -0.3048)
			(end 0.67945 -0.3048)
			(stroke
				(width 0.1)
				(type default)
			)
			(layer "F.Fab")
		)
		(fp_line
			(start 0.12065 -0.2794)
			(end 0.12065 -0.3048)
			(stroke
				(width 0.1)
				(type default)
			)
			(layer "F.Fab")
		)
		(fp_line
			(start -0.12065 -0.2794)
			(end 0.12065 -0.2794)
			(stroke
				(width 0.1)
				(type default)
			)
			(layer "F.Fab")
		)
		(fp_line
			(start 0.120396 0.2794)
			(end -0.12065 0.2794)
			(stroke
				(width 0.1)
				(type default)
			)
			(layer "F.Fab")
		)
		(fp_line
			(start -0.12065 0.2794)
			(end -0.12065 0.3048)
			(stroke
				(width 0.1)
				(type default)
			)
			(layer "F.Fab")
		)
		(fp_line
			(start 0.67945 0.3048)
			(end 0.120396 0.3048)
			(stroke
				(width 0.1)
				(type default)
			)
			(layer "F.Fab")
		)
		(fp_line
			(start 0.120396 0.3048)
			(end 0.120396 0.2794)
			(stroke
				(width 0.1)
				(type default)
			)
			(layer "F.Fab")
		)
		(fp_line
			(start -0.12065 0.3048)
			(end -0.67945 0.3048)
			(stroke
				(width 0.1)
				(type default)
			)
			(layer "F.Fab")
		)
		(fp_line
			(start -0.67945 0.3048)
			(end -0.67945 -0.305054)
			(stroke
				(width 0.1)
				(type default)
			)
			(layer "F.Fab")
		)
		(pad "1" smd circle
			(at -0.40005 0 90)
			(size 0 0)
			(layers "F.Cu" "F.Mask" "F.Paste")
			(net "P12V_AUX_UV_TRIGGER")
		)
		(pad "2" smd circle
			(at 0.40005 0 90)
			(size 0 0)
			(layers "F.Cu" "F.Mask" "F.Paste")
			(net "IRQ_UV_DETECT_R2_N")
		)
	)
	(footprint ""
		(layer "F.Cu")
		(at 294.899588 -362.584746 -90)
		(property "Reference" "PC1212_P0_2"
			(at 0 0 270)
			(layer "F.SilkS")
			(hide yes)
			(effects
				(font
					(size 1.27 1.27)
				)
			)
		)
		(property "Value" ""
			(at 0 0 270)
			(layer "F.Fab")
			(effects
				(font
					(size 1.27 1.27)
				)
			)
		)
		(duplicate_pad_numbers_are_jumpers no)
		(fp_line
			(start -0.7874 0.4064)
			(end -0.7874 -0.4064)
			(stroke
				(width 0.1524)
				(type default)
			)
			(layer "F.SilkS")
		)
		(fp_line
			(start 0.7874 0.4064)
			(end -0.7874 0.4064)
			(stroke
				(width 0.1524)
				(type default)
			)
			(layer "F.SilkS")
		)
		(fp_line
			(start -0.7874 -0.4064)
			(end 0.7874 -0.4064)
			(stroke
				(width 0.1524)
				(type default)
			)
			(layer "F.SilkS")
		)
		(fp_line
			(start 0.7874 -0.4064)
			(end 0.7874 0.4064)
			(stroke
				(width 0.1524)
				(type default)
			)
			(layer "F.SilkS")
		)
		(fp_line
			(start -0.67945 0.3048)
			(end -0.67945 -0.305054)
			(stroke
				(width 0.1)
				(type default)
			)
			(layer "F.Fab")
		)
		(fp_line
			(start -0.12065 0.3048)
			(end -0.67945 0.3048)
			(stroke
				(width 0.1)
				(type default)
			)
			(layer "F.Fab")
		)
		(fp_line
			(start 0.120396 0.3048)
			(end 0.120396 0.2794)
			(stroke
				(width 0.1)
				(type default)
			)
			(layer "F.Fab")
		)
		(fp_line
			(start 0.67945 0.3048)
			(end 0.120396 0.3048)
			(stroke
				(width 0.1)
				(type default)
			)
			(layer "F.Fab")
		)
		(fp_line
			(start -0.12065 0.2794)
			(end -0.12065 0.3048)
			(stroke
				(width 0.1)
				(type default)
			)
			(layer "F.Fab")
		)
		(fp_line
			(start 0.120396 0.2794)
			(end -0.12065 0.2794)
			(stroke
				(width 0.1)
				(type default)
			)
			(layer "F.Fab")
		)
		(fp_line
			(start -0.12065 -0.2794)
			(end 0.12065 -0.2794)
			(stroke
				(width 0.1)
				(type default)
			)
			(layer "F.Fab")
		)
		(fp_line
			(start 0.12065 -0.2794)
			(end 0.12065 -0.3048)
			(stroke
				(width 0.1)
				(type default)
			)
			(layer "F.Fab")
		)
		(fp_line
			(start 0.12065 -0.3048)
			(end 0.67945 -0.3048)
			(stroke
				(width 0.1)
				(type default)
			)
			(layer "F.Fab")
		)
		(fp_line
			(start 0.67945 -0.3048)
			(end 0.67945 0.3048)
			(stroke
				(width 0.1)
				(type default)
			)
			(layer "F.Fab")
		)
		(fp_line
			(start -0.67945 -0.305054)
			(end -0.12065 -0.305054)
			(stroke
				(width 0.1)
				(type default)
			)
			(layer "F.Fab")
		)
		(fp_line
			(start -0.12065 -0.305054)
			(end -0.12065 -0.2794)
			(stroke
				(width 0.1)
				(type default)
			)
			(layer "F.Fab")
		)
		(pad "1" smd circle
			(at -0.40005 0 270)
			(size 0 0)
			(layers "F.Cu" "F.Mask" "F.Paste")
			(net "PVCCFA_EHV_FIVRA_CPU0_PVCC2")
		)
		(pad "2" smd circle
			(at 0.40005 0 270)
			(size 0 0)
			(layers "F.Cu" "F.Mask" "F.Paste")
			(net "GND")
		)
	)
	(footprint ""
		(layer "F.Cu")
		(at 275.323046 -15.093188)
		(property "Reference" "U219"
			(at -5.59308 0.464312 0)
			(unlocked yes)
			(layer "F.SilkS")
			(effects
				(font
					(size 0.7874 0.5842)
					(thickness 0.1524)
				)
				(justify left)
			)
		)
		(property "Value" ""
			(at 0 0 0)
			(layer "F.Fab")
			(effects
				(font
					(size 1.27 1.27)
				)
			)
		)
		(duplicate_pad_numbers_are_jumpers no)
		(fp_line
			(start -1.733296 -1.549908)
			(end -1.733296 1.549908)
			(stroke
				(width 0.1524)
				(type default)
			)
			(layer "F.SilkS")
		)
		(fp_line
			(start -1.733296 1.549908)
			(end 1.733296 1.549908)
			(stroke
				(width 0.1524)
				(type default)
			)
			(layer "F.SilkS")
		)
		(fp_line
			(start -0.660908 -1.549908)
			(end -1.733296 -1.549908)
			(stroke
				(width 0.1524)
				(type default)
			)
			(layer "F.SilkS")
		)
		(fp_line
			(start 0 -0.889)
			(end -0.660908 -1.549908)
			(stroke
				(width 0.1524)
				(type default)
			)
			(layer "F.SilkS")
		)
		(fp_line
			(start 0.660908 -1.549908)
			(end 0 -0.889)
			(stroke
				(width 0.1524)
				(type default)
			)
			(layer "F.SilkS")
		)
		(fp_line
			(start 1.733296 -1.549908)
			(end 0.660908 -1.549908)
			(stroke
				(width 0.1524)
				(type default)
			)
			(layer "F.SilkS")
		)
		(fp_line
			(start 1.733296 1.549908)
			(end 1.733296 -1.549908)
			(stroke
				(width 0.1524)
				(type default)
			)
			(layer "F.SilkS")
		)
		(fp_poly
			(pts
				(xy -2.4384 -1.20396) (xy -1.9304 -0.94996) (xy -2.4384 -0.69596)
			)
			(stroke
				(width 0)
				(type default)
			)
			(fill yes)
			(layer "F.SilkS")
		)
		(fp_line
			(start -0.849884 -1.549908)
			(end -0.849884 1.549908)
			(stroke
				(width 0.1)
				(type default)
			)
			(layer "F.Fab")
		)
		(fp_line
			(start -0.849884 1.549908)
			(end 0.849884 1.549908)
			(stroke
				(width 0.1)
				(type default)
			)
			(layer "F.Fab")
		)
		(fp_line
			(start 0.849884 -1.549908)
			(end -0.849884 -1.549908)
			(stroke
				(width 0.1)
				(type default)
			)
			(layer "F.Fab")
		)
		(fp_line
			(start 0.849884 1.549908)
			(end 0.849884 -1.549908)
			(stroke
				(width 0.1)
				(type default)
			)
			(layer "F.Fab")
		)
		(fp_poly
			(pts
				(xy -2.4384 -1.20396) (xy -2.4384 -0.69596) (xy -1.9304 -0.94996)
			)
			(stroke
				(width 0)
				(type default)
			)
			(fill yes)
			(layer "F.Fab")
		)
		(pad "1" smd rect
			(at -1.199896 -0.94996 270)
			(size 0.5588 0.8128)
			(layers "F.Cu" "F.Mask" "F.Paste")
			(net "NC_U219_NC1")
		)
		(pad "2" smd rect
			(at -1.199896 0 270)
			(size 0.5588 0.8128)
			(layers "F.Cu" "F.Mask" "F.Paste")
			(net "OCP_V3_2_WAKE_BUFF_R_N")
		)
		(pad "3" smd rect
			(at -1.199896 0.94996 270)
			(size 0.5588 0.8128)
			(layers "F.Cu" "F.Mask" "F.Paste")
			(net "GND")
		)
		(pad "4" smd rect
			(at 1.199896 0.94996 270)
			(size 0.5588 0.8128)
			(layers "F.Cu" "F.Mask" "F.Paste")
			(net "IRQ_LVC3_V3_2_WAKE_BUF_N")
		)
		(pad "5" smd rect
			(at 1.199896 -0.94996 270)
			(size 0.5588 0.8128)
			(layers "F.Cu" "F.Mask" "F.Paste")
			(net "P3V3_AUX")
		)
	)
	(footprint ""
		(layer "F.Cu")
		(at 369.190778 -391.797286 180)
		(property "Reference" "R4166"
			(at 0 0 180)
			(layer "F.SilkS")
			(hide yes)
			(effects
				(font
					(size 1.27 1.27)
				)
			)
		)
		(property "Value" ""
			(at 0 0 180)
			(layer "F.Fab")
			(effects
				(font
					(size 1.27 1.27)
				)
			)
		)
		(duplicate_pad_numbers_are_jumpers no)
		(fp_line
			(start 0.7874 0.4064)
			(end -0.7874 0.4064)
			(stroke
				(width 0.1524)
				(type default)
			)
			(layer "F.SilkS")
		)
		(fp_line
			(start 0.7874 -0.4064)
			(end 0.7874 0.4064)
			(stroke
				(width 0.1524)
				(type default)
			)
			(layer "F.SilkS")
		)
		(fp_line
			(start -0.7874 0.4064)
			(end -0.7874 -0.4064)
			(stroke
				(width 0.1524)
				(type default)
			)
			(layer "F.SilkS")
		)
		(fp_line
			(start -0.7874 -0.4064)
			(end 0.7874 -0.4064)
			(stroke
				(width 0.1524)
				(type default)
			)
			(layer "F.SilkS")
		)
		(fp_line
			(start 0.67945 0.3048)
			(end 0.120396 0.3048)
			(stroke
				(width 0.1)
				(type default)
			)
			(layer "F.Fab")
		)
		(fp_line
			(start 0.67945 -0.3048)
			(end 0.67945 0.3048)
			(stroke
				(width 0.1)
				(type default)
			)
			(layer "F.Fab")
		)
		(fp_line
			(start 0.12065 -0.2794)
			(end 0.12065 -0.3048)
			(stroke
				(width 0.1)
				(type default)
			)
			(layer "F.Fab")
		)
		(fp_line
			(start 0.12065 -0.3048)
			(end 0.67945 -0.3048)
			(stroke
				(width 0.1)
				(type default)
			)
			(layer "F.Fab")
		)
		(fp_line
			(start 0.120396 0.3048)
			(end 0.120396 0.2794)
			(stroke
				(width 0.1)
				(type default)
			)
			(layer "F.Fab")
		)
		(fp_line
			(start 0.120396 0.2794)
			(end -0.12065 0.2794)
			(stroke
				(width 0.1)
				(type default)
			)
			(layer "F.Fab")
		)
		(fp_line
			(start -0.12065 0.3048)
			(end -0.67945 0.3048)
			(stroke
				(width 0.1)
				(type default)
			)
			(layer "F.Fab")
		)
		(fp_line
			(start -0.12065 0.2794)
			(end -0.12065 0.3048)
			(stroke
				(width 0.1)
				(type default)
			)
			(layer "F.Fab")
		)
		(fp_line
			(start -0.12065 -0.2794)
			(end 0.12065 -0.2794)
			(stroke
				(width 0.1)
				(type default)
			)
			(layer "F.Fab")
		)
		(fp_line
			(start -0.12065 -0.305054)
			(end -0.12065 -0.2794)
			(stroke
				(width 0.1)
				(type default)
			)
			(layer "F.Fab")
		)
		(fp_line
			(start -0.67945 0.3048)
			(end -0.67945 -0.305054)
			(stroke
				(width 0.1)
				(type default)
			)
			(layer "F.Fab")
		)
		(fp_line
			(start -0.67945 -0.305054)
			(end -0.12065 -0.305054)
			(stroke
				(width 0.1)
				(type default)
			)
			(layer "F.Fab")
		)
		(pad "1" smd circle
			(at -0.40005 0 180)
			(size 0 0)
			(layers "F.Cu" "F.Mask" "F.Paste")
			(net "P3V3_AUX")
		)
		(pad "2" smd circle
			(at 0.40005 0 180)
			(size 0 0)
			(layers "F.Cu" "F.Mask" "F.Paste")
			(net "GPU_3V3IO_RSVD3_N")
		)
	)
	(footprint ""
		(layer "F.Cu")
		(at 279.40762 -426.68698)
		(property "Reference" "C4562"
			(at 0 0 0)
			(layer "F.SilkS")
			(hide yes)
			(effects
				(font
					(size 1.27 1.27)
				)
			)
		)
		(property "Value" ""
			(at 0 0 0)
			(layer "F.Fab")
			(effects
				(font
					(size 1.27 1.27)
				)
			)
		)
		(duplicate_pad_numbers_are_jumpers no)
		(fp_line
			(start -0.7874 -0.4064)
			(end 0.7874 -0.4064)
			(stroke
				(width 0.1524)
				(type default)
			)
			(layer "F.SilkS")
		)
		(fp_line
			(start -0.7874 0.4064)
			(end -0.7874 -0.4064)
			(stroke
				(width 0.1524)
				(type default)
			)
			(layer "F.SilkS")
		)
		(fp_line
			(start 0.7874 -0.4064)
			(end 0.7874 0.4064)
			(stroke
				(width 0.1524)
				(type default)
			)
			(layer "F.SilkS")
		)
		(fp_line
			(start 0.7874 0.4064)
			(end -0.7874 0.4064)
			(stroke
				(width 0.1524)
				(type default)
			)
			(layer "F.SilkS")
		)
		(fp_line
			(start -0.67945 -0.305054)
			(end -0.12065 -0.305054)
			(stroke
				(width 0.1)
				(type default)
			)
			(layer "F.Fab")
		)
		(fp_line
			(start -0.67945 0.3048)
			(end -0.67945 -0.305054)
			(stroke
				(width 0.1)
				(type default)
			)
			(layer "F.Fab")
		)
		(fp_line
			(start -0.12065 -0.305054)
			(end -0.12065 -0.2794)
			(stroke
				(width 0.1)
				(type default)
			)
			(layer "F.Fab")
		)
		(fp_line
			(start -0.12065 -0.2794)
			(end 0.12065 -0.2794)
			(stroke
				(width 0.1)
				(type default)
			)
			(layer "F.Fab")
		)
		(fp_line
			(start -0.12065 0.2794)
			(end -0.12065 0.3048)
			(stroke
				(width 0.1)
				(type default)
			)
			(layer "F.Fab")
		)
		(fp_line
			(start -0.12065 0.3048)
			(end -0.67945 0.3048)
			(stroke
				(width 0.1)
				(type default)
			)
			(layer "F.Fab")
		)
		(fp_line
			(start 0.120396 0.2794)
			(end -0.12065 0.2794)
			(stroke
				(width 0.1)
				(type default)
			)
			(layer "F.Fab")
		)
		(fp_line
			(start 0.120396 0.3048)
			(end 0.120396 0.2794)
			(stroke
				(width 0.1)
				(type default)
			)
			(layer "F.Fab")
		)
		(fp_line
			(start 0.12065 -0.3048)
			(end 0.67945 -0.3048)
			(stroke
				(width 0.1)
				(type default)
			)
			(layer "F.Fab")
		)
		(fp_line
			(start 0.12065 -0.2794)
			(end 0.12065 -0.3048)
			(stroke
				(width 0.1)
				(type default)
			)
			(layer "F.Fab")
		)
		(fp_line
			(start 0.67945 -0.3048)
			(end 0.67945 0.3048)
			(stroke
				(width 0.1)
				(type default)
			)
			(layer "F.Fab")
		)
		(fp_line
			(start 0.67945 0.3048)
			(end 0.120396 0.3048)
			(stroke
				(width 0.1)
				(type default)
			)
			(layer "F.Fab")
		)
		(pad "1" smd circle
			(at -0.40005 0)
			(size 0 0)
			(layers "F.Cu" "F.Mask" "F.Paste")
			(net "U369_VDD")
		)
		(pad "2" smd circle
			(at 0.40005 0)
			(size 0 0)
			(layers "F.Cu" "F.Mask" "F.Paste")
			(net "GND")
		)
	)
	(footprint ""
		(layer "F.Cu")
		(at 172.878242 -28.03779 90)
		(property "Reference" "PR4010"
			(at 0 0 90)
			(layer "F.SilkS")
			(hide yes)
			(effects
				(font
					(size 1.27 1.27)
				)
			)
		)
		(property "Value" ""
			(at 0 0 90)
			(layer "F.Fab")
			(effects
				(font
					(size 1.27 1.27)
				)
			)
		)
		(duplicate_pad_numbers_are_jumpers no)
		(fp_line
			(start 0.7874 -0.4064)
			(end 0.7874 0.4064)
			(stroke
				(width 0.1524)
				(type default)
			)
			(layer "F.SilkS")
		)
		(fp_line
			(start -0.7874 -0.4064)
			(end 0.7874 -0.4064)
			(stroke
				(width 0.1524)
				(type default)
			)
			(layer "F.SilkS")
		)
		(fp_line
			(start 0.7874 0.4064)
			(end -0.7874 0.4064)
			(stroke
				(width 0.1524)
				(type default)
			)
			(layer "F.SilkS")
		)
		(fp_line
			(start -0.7874 0.4064)
			(end -0.7874 -0.4064)
			(stroke
				(width 0.1524)
				(type default)
			)
			(layer "F.SilkS")
		)
		(fp_line
			(start -0.12065 -0.305054)
			(end -0.12065 -0.2794)
			(stroke
				(width 0.1)
				(type default)
			)
			(layer "F.Fab")
		)
		(fp_line
			(start -0.67945 -0.305054)
			(end -0.12065 -0.305054)
			(stroke
				(width 0.1)
				(type default)
			)
			(layer "F.Fab")
		)
		(fp_line
			(start 0.67945 -0.3048)
			(end 0.67945 0.3048)
			(stroke
				(width 0.1)
				(type default)
			)
			(layer "F.Fab")
		)
		(fp_line
			(start 0.12065 -0.3048)
			(end 0.67945 -0.3048)
			(stroke
				(width 0.1)
				(type default)
			)
			(layer "F.Fab")
		)
		(fp_line
			(start 0.12065 -0.2794)
			(end 0.12065 -0.3048)
			(stroke
				(width 0.1)
				(type default)
			)
			(layer "F.Fab")
		)
		(fp_line
			(start -0.12065 -0.2794)
			(end 0.12065 -0.2794)
			(stroke
				(width 0.1)
				(type default)
			)
			(layer "F.Fab")
		)
		(fp_line
			(start 0.120396 0.2794)
			(end -0.12065 0.2794)
			(stroke
				(width 0.1)
				(type default)
			)
			(layer "F.Fab")
		)
		(fp_line
			(start -0.12065 0.2794)
			(end -0.12065 0.3048)
			(stroke
				(width 0.1)
				(type default)
			)
			(layer "F.Fab")
		)
		(fp_line
			(start 0.67945 0.3048)
			(end 0.120396 0.3048)
			(stroke
				(width 0.1)
				(type default)
			)
			(layer "F.Fab")
		)
		(fp_line
			(start 0.120396 0.3048)
			(end 0.120396 0.2794)
			(stroke
				(width 0.1)
				(type default)
			)
			(layer "F.Fab")
		)
		(fp_line
			(start -0.12065 0.3048)
			(end -0.67945 0.3048)
			(stroke
				(width 0.1)
				(type default)
			)
			(layer "F.Fab")
		)
		(fp_line
			(start -0.67945 0.3048)
			(end -0.67945 -0.305054)
			(stroke
				(width 0.1)
				(type default)
			)
			(layer "F.Fab")
		)
		(pad "1" smd circle
			(at -0.40005 0 90)
			(size 0 0)
			(layers "F.Cu" "F.Mask" "F.Paste")
			(net "P12V_AUX")
		)
		(pad "2" smd circle
			(at 0.40005 0 90)
			(size 0 0)
			(layers "F.Cu" "F.Mask" "F.Paste")
			(net "P12V_SCM_OV_FB")
		)
	)
)
